(kicad_pcb
	(version 20260206)
	(generator "pcbnew")
	(generator_version "10.0")
	(general
		(thickness 1.6)
		(legacy_teardrops no)
	)
	(paper "A4")
	(title_block
		(title "03242023_DA0F0TMBIJ0_F0T_Motherboard_J_brd_V01_OCP.brd")
		(comment 1 "Grand Teton / footprints 1254-1259 of 6105")
	)
	(layers
		(0 "F.Cu" signal "TOP")
		(4 "In1.Cu" signal "GND")
		(6 "In2.Cu" signal "IN1")
		(8 "In3.Cu" signal "GND1")
		(10 "In4.Cu" signal "IN2")
		(12 "In5.Cu" signal "GND2")
		(14 "In6.Cu" signal "IN3")
		(16 "In7.Cu" signal "GND3")
		(18 "In8.Cu" signal "VCC")
		(20 "In9.Cu" signal "VCC1")
		(22 "In10.Cu" signal "GND4")
		(24 "In11.Cu" signal "IN4")
		(26 "In12.Cu" signal "GND5")
		(28 "In13.Cu" signal "IN5")
		(30 "In14.Cu" signal "GND6")
		(32 "In15.Cu" signal "IN6")
		(34 "In16.Cu" signal "GND7")
		(2 "B.Cu" signal "BOTTOM")
		(9 "F.Adhes" user "F.Adhesive")
		(11 "B.Adhes" user "B.Adhesive")
		(13 "F.Paste" user "Package Geometry/Pastemask Top")
		(15 "B.Paste" user "Package Geometry/Pastemask Bottom")
		(5 "F.SilkS" user "Ref Des/Silkscreen Top")
		(7 "B.SilkS" user "Ref Des/Silkscreen Bottom")
		(1 "F.Mask" user "Board Geometry/Soldermask Top")
		(3 "B.Mask" user "Board Geometry/Soldermask Bottom")
		(17 "Dwgs.User" user "User.Drawings")
		(19 "Cmts.User" user "User.Comments")
		(21 "Eco1.User" user "User.Eco1")
		(23 "Eco2.User" user "User.Eco2")
		(25 "Edge.Cuts" user "Board Geometry/Outline")
		(27 "Margin" user)
		(31 "F.CrtYd" user "Package Geometry/Place Bound Top")
		(29 "B.CrtYd" user "Package Geometry/Place Bound Bottom")
		(35 "F.Fab" user "Ref Des/Assembly Top")
		(33 "B.Fab" user "Ref Des/Assembly Bottom")
	)
	(footprint ""
		(layer "F.Cu")
		(at 114.243612 -365.158274 90)
		(property "Reference" "PC553"
			(at 0 0 90)
			(layer "F.SilkS")
			(hide yes)
			(effects
				(font
					(size 1.27 1.27)
				)
			)
		)
		(property "Value" ""
			(at 0 0 90)
			(layer "F.Fab")
			(effects
				(font
					(size 1.27 1.27)
				)
			)
		)
		(duplicate_pad_numbers_are_jumpers no)
		(fp_line
			(start 0.7874 -0.4064)
			(end 0.7874 0.4064)
			(stroke
				(width 0.1524)
				(type default)
			)
			(layer "F.SilkS")
		)
		(fp_line
			(start -0.7874 -0.4064)
			(end 0.7874 -0.4064)
			(stroke
				(width 0.1524)
				(type default)
			)
			(layer "F.SilkS")
		)
		(fp_line
			(start 0.7874 0.4064)
			(end -0.7874 0.4064)
			(stroke
				(width 0.1524)
				(type default)
			)
			(layer "F.SilkS")
		)
		(fp_line
			(start -0.7874 0.4064)
			(end -0.7874 -0.4064)
			(stroke
				(width 0.1524)
				(type default)
			)
			(layer "F.SilkS")
		)
		(fp_line
			(start -0.12065 -0.305054)
			(end -0.12065 -0.2794)
			(stroke
				(width 0.1)
				(type default)
			)
			(layer "F.Fab")
		)
		(fp_line
			(start -0.67945 -0.305054)
			(end -0.12065 -0.305054)
			(stroke
				(width 0.1)
				(type default)
			)
			(layer "F.Fab")
		)
		(fp_line
			(start 0.67945 -0.3048)
			(end 0.67945 0.3048)
			(stroke
				(width 0.1)
				(type default)
			)
			(layer "F.Fab")
		)
		(fp_line
			(start 0.12065 -0.3048)
			(end 0.67945 -0.3048)
			(stroke
				(width 0.1)
				(type default)
			)
			(layer "F.Fab")
		)
		(fp_line
			(start 0.12065 -0.2794)
			(end 0.12065 -0.3048)
			(stroke
				(width 0.1)
				(type default)
			)
			(layer "F.Fab")
		)
		(fp_line
			(start -0.12065 -0.2794)
			(end 0.12065 -0.2794)
			(stroke
				(width 0.1)
				(type default)
			)
			(layer "F.Fab")
		)
		(fp_line
			(start 0.120396 0.2794)
			(end -0.12065 0.2794)
			(stroke
				(width 0.1)
				(type default)
			)
			(layer "F.Fab")
		)
		(fp_line
			(start -0.12065 0.2794)
			(end -0.12065 0.3048)
			(stroke
				(width 0.1)
				(type default)
			)
			(layer "F.Fab")
		)
		(fp_line
			(start 0.67945 0.3048)
			(end 0.120396 0.3048)
			(stroke
				(width 0.1)
				(type default)
			)
			(layer "F.Fab")
		)
		(fp_line
			(start 0.120396 0.3048)
			(end 0.120396 0.2794)
			(stroke
				(width 0.1)
				(type default)
			)
			(layer "F.Fab")
		)
		(fp_line
			(start -0.12065 0.3048)
			(end -0.67945 0.3048)
			(stroke
				(width 0.1)
				(type default)
			)
			(layer "F.Fab")
		)
		(fp_line
			(start -0.67945 0.3048)
			(end -0.67945 -0.305054)
			(stroke
				(width 0.1)
				(type default)
			)
			(layer "F.Fab")
		)
		(pad "1" smd circle
			(at -0.40005 0 90)
			(size 0 0)
			(layers "F.Cu" "F.Mask" "F.Paste")
			(net "PVCCIN_CPU1_VREF")
		)
		(pad "2" smd circle
			(at 0.40005 0 90)
			(size 0 0)
			(layers "F.Cu" "F.Mask" "F.Paste")
			(net "GND")
		)
	)
	(footprint ""
		(layer "F.Cu")
		(at 184.96788 -97.119948 -90)
		(property "Reference" "R1398"
			(at 0 0 270)
			(layer "F.SilkS")
			(hide yes)
			(effects
				(font
					(size 1.27 1.27)
				)
			)
		)
		(property "Value" ""
			(at 0 0 270)
			(layer "F.Fab")
			(effects
				(font
					(size 1.27 1.27)
				)
			)
		)
		(duplicate_pad_numbers_are_jumpers no)
		(fp_line
			(start -0.7874 0.4064)
			(end -0.7874 -0.4064)
			(stroke
				(width 0.1524)
				(type default)
			)
			(layer "F.SilkS")
		)
		(fp_line
			(start 0.7874 0.4064)
			(end -0.7874 0.4064)
			(stroke
				(width 0.1524)
				(type default)
			)
			(layer "F.SilkS")
		)
		(fp_line
			(start -0.7874 -0.4064)
			(end 0.7874 -0.4064)
			(stroke
				(width 0.1524)
				(type default)
			)
			(layer "F.SilkS")
		)
		(fp_line
			(start 0.7874 -0.4064)
			(end 0.7874 0.4064)
			(stroke
				(width 0.1524)
				(type default)
			)
			(layer "F.SilkS")
		)
		(fp_line
			(start -0.67945 0.3048)
			(end -0.67945 -0.305054)
			(stroke
				(width 0.1)
				(type default)
			)
			(layer "F.Fab")
		)
		(fp_line
			(start -0.12065 0.3048)
			(end -0.67945 0.3048)
			(stroke
				(width 0.1)
				(type default)
			)
			(layer "F.Fab")
		)
		(fp_line
			(start 0.120396 0.3048)
			(end 0.120396 0.2794)
			(stroke
				(width 0.1)
				(type default)
			)
			(layer "F.Fab")
		)
		(fp_line
			(start 0.67945 0.3048)
			(end 0.120396 0.3048)
			(stroke
				(width 0.1)
				(type default)
			)
			(layer "F.Fab")
		)
		(fp_line
			(start -0.12065 0.2794)
			(end -0.12065 0.3048)
			(stroke
				(width 0.1)
				(type default)
			)
			(layer "F.Fab")
		)
		(fp_line
			(start 0.120396 0.2794)
			(end -0.12065 0.2794)
			(stroke
				(width 0.1)
				(type default)
			)
			(layer "F.Fab")
		)
		(fp_line
			(start -0.12065 -0.2794)
			(end 0.12065 -0.2794)
			(stroke
				(width 0.1)
				(type default)
			)
			(layer "F.Fab")
		)
		(fp_line
			(start 0.12065 -0.2794)
			(end 0.12065 -0.3048)
			(stroke
				(width 0.1)
				(type default)
			)
			(layer "F.Fab")
		)
		(fp_line
			(start 0.12065 -0.3048)
			(end 0.67945 -0.3048)
			(stroke
				(width 0.1)
				(type default)
			)
			(layer "F.Fab")
		)
		(fp_line
			(start 0.67945 -0.3048)
			(end 0.67945 0.3048)
			(stroke
				(width 0.1)
				(type default)
			)
			(layer "F.Fab")
		)
		(fp_line
			(start -0.67945 -0.305054)
			(end -0.12065 -0.305054)
			(stroke
				(width 0.1)
				(type default)
			)
			(layer "F.Fab")
		)
		(fp_line
			(start -0.12065 -0.305054)
			(end -0.12065 -0.2794)
			(stroke
				(width 0.1)
				(type default)
			)
			(layer "F.Fab")
		)
		(pad "1" smd circle
			(at -0.40005 0 270)
			(size 0 0)
			(layers "F.Cu" "F.Mask" "F.Paste")
			(net "PWRGD_CPU1_LVC1_R")
		)
		(pad "2" smd circle
			(at 0.40005 0 270)
			(size 0 0)
			(layers "F.Cu" "F.Mask" "F.Paste")
			(net "GND")
		)
	)
	(footprint ""
		(layer "F.Cu")
		(at 420.682166 -136.162034 180)
		(property "Reference" "PC214"
			(at 0 0 180)
			(layer "F.SilkS")
			(hide yes)
			(effects
				(font
					(size 1.27 1.27)
				)
			)
		)
		(property "Value" ""
			(at 0 0 180)
			(layer "F.Fab")
			(effects
				(font
					(size 1.27 1.27)
				)
			)
		)
		(duplicate_pad_numbers_are_jumpers no)
		(fp_line
			(start 0.7874 0.4064)
			(end -0.7874 0.4064)
			(stroke
				(width 0.1524)
				(type default)
			)
			(layer "F.SilkS")
		)
		(fp_line
			(start 0.7874 -0.4064)
			(end 0.7874 0.4064)
			(stroke
				(width 0.1524)
				(type default)
			)
			(layer "F.SilkS")
		)
		(fp_line
			(start -0.7874 0.4064)
			(end -0.7874 -0.4064)
			(stroke
				(width 0.1524)
				(type default)
			)
			(layer "F.SilkS")
		)
		(fp_line
			(start -0.7874 -0.4064)
			(end 0.7874 -0.4064)
			(stroke
				(width 0.1524)
				(type default)
			)
			(layer "F.SilkS")
		)
		(fp_line
			(start 0.67945 0.3048)
			(end 0.120396 0.3048)
			(stroke
				(width 0.1)
				(type default)
			)
			(layer "F.Fab")
		)
		(fp_line
			(start 0.67945 -0.3048)
			(end 0.67945 0.3048)
			(stroke
				(width 0.1)
				(type default)
			)
			(layer "F.Fab")
		)
		(fp_line
			(start 0.12065 -0.2794)
			(end 0.12065 -0.3048)
			(stroke
				(width 0.1)
				(type default)
			)
			(layer "F.Fab")
		)
		(fp_line
			(start 0.12065 -0.3048)
			(end 0.67945 -0.3048)
			(stroke
				(width 0.1)
				(type default)
			)
			(layer "F.Fab")
		)
		(fp_line
			(start 0.120396 0.3048)
			(end 0.120396 0.2794)
			(stroke
				(width 0.1)
				(type default)
			)
			(layer "F.Fab")
		)
		(fp_line
			(start 0.120396 0.2794)
			(end -0.12065 0.2794)
			(stroke
				(width 0.1)
				(type default)
			)
			(layer "F.Fab")
		)
		(fp_line
			(start -0.12065 0.3048)
			(end -0.67945 0.3048)
			(stroke
				(width 0.1)
				(type default)
			)
			(layer "F.Fab")
		)
		(fp_line
			(start -0.12065 0.2794)
			(end -0.12065 0.3048)
			(stroke
				(width 0.1)
				(type default)
			)
			(layer "F.Fab")
		)
		(fp_line
			(start -0.12065 -0.2794)
			(end 0.12065 -0.2794)
			(stroke
				(width 0.1)
				(type default)
			)
			(layer "F.Fab")
		)
		(fp_line
			(start -0.12065 -0.305054)
			(end -0.12065 -0.2794)
			(stroke
				(width 0.1)
				(type default)
			)
			(layer "F.Fab")
		)
		(fp_line
			(start -0.67945 0.3048)
			(end -0.67945 -0.305054)
			(stroke
				(width 0.1)
				(type default)
			)
			(layer "F.Fab")
		)
		(fp_line
			(start -0.67945 -0.305054)
			(end -0.12065 -0.305054)
			(stroke
				(width 0.1)
				(type default)
			)
			(layer "F.Fab")
		)
		(pad "1" smd circle
			(at -0.40005 0 180)
			(size 0 0)
			(layers "F.Cu" "F.Mask" "F.Paste")
			(net "PVCCINFAON_CPU0_CSPIN")
		)
		(pad "2" smd circle
			(at 0.40005 0 180)
			(size 0 0)
			(layers "F.Cu" "F.Mask" "F.Paste")
			(net "GND")
		)
	)
	(footprint ""
		(layer "F.Cu")
		(at 239.152684 -52.92725 180)
		(property "Reference" "C1996"
			(at 0 0 180)
			(layer "F.SilkS")
			(hide yes)
			(effects
				(font
					(size 1.27 1.27)
				)
			)
		)
		(property "Value" ""
			(at 0 0 180)
			(layer "F.Fab")
			(effects
				(font
					(size 1.27 1.27)
				)
			)
		)
		(duplicate_pad_numbers_are_jumpers no)
		(fp_line
			(start 0.299974 0.150114)
			(end -0.299974 0.150114)
			(stroke
				(width 0.1)
				(type default)
			)
			(layer "F.Fab")
		)
		(fp_line
			(start 0.299974 -0.150114)
			(end 0.299974 0.150114)
			(stroke
				(width 0.1)
				(type default)
			)
			(layer "F.Fab")
		)
		(fp_line
			(start -0.299974 0.150114)
			(end -0.299974 -0.150114)
			(stroke
				(width 0.1)
				(type default)
			)
			(layer "F.Fab")
		)
		(fp_line
			(start -0.299974 -0.150114)
			(end 0.299974 -0.150114)
			(stroke
				(width 0.1)
				(type default)
			)
			(layer "F.Fab")
		)
		(pad "1" smd rect
			(at -0.2667 0 180)
			(size 0.3048 0.381)
			(layers "F.Cu" "F.Mask" "F.Paste")
			(net "P3E_PCH_E1S_TX_DN<0>")
		)
		(pad "2" smd rect
			(at 0.2667 0 180)
			(size 0.3048 0.381)
			(layers "F.Cu" "F.Mask" "F.Paste")
			(net "P3E_PCH_E1S_TX_C_DN<0>")
		)
		(zone
			(layer "In1.Cu")
			(hatch none 0.5)
			(connect_pads
				(clearance 0)
			)
			(min_thickness 0.25)
			(keepout
				(tracks not_allowed)
				(vias allowed)
				(pads allowed)
				(copperpour not_allowed)
				(footprints allowed)
			)
			(placement
				(enabled no)
				(sheetname "")
			)
			(fill
				(thermal_gap 0.5)
				(thermal_bridge_width 0.5)
				(island_removal_mode 0)
			)
			(polygon
				(pts
					(arc
						(start 239.012984 -53.167534)
						(mid 239.066866 -53.145216)
						(end 239.089184 -53.091334)
					)
					(arc
						(start 239.089184 -52.761134)
						(mid 239.066866 -52.707252)
						(end 239.012984 -52.684934)
					)
					(arc
						(start 238.758984 -52.684934)
						(mid 238.705102 -52.707252)
						(end 238.682784 -52.761134)
					)
					(arc
						(start 238.682784 -53.091334)
						(mid 238.705102 -53.145216)
						(end 238.758984 -53.167534)
					)
				)
			)
		)
		(zone
			(layer "In1.Cu")
			(hatch none 0.5)
			(connect_pads
				(clearance 0)
			)
			(min_thickness 0.25)
			(keepout
				(tracks not_allowed)
				(vias allowed)
				(pads allowed)
				(copperpour not_allowed)
				(footprints allowed)
			)
			(placement
				(enabled no)
				(sheetname "")
			)
			(fill
				(thermal_gap 0.5)
				(thermal_bridge_width 0.5)
				(island_removal_mode 0)
			)
			(polygon
				(pts
					(arc
						(start 239.546384 -53.167534)
						(mid 239.600266 -53.145216)
						(end 239.622584 -53.091334)
					)
					(arc
						(start 239.622584 -52.761134)
						(mid 239.600266 -52.707252)
						(end 239.546384 -52.684934)
					)
					(arc
						(start 239.292384 -52.684934)
						(mid 239.238502 -52.707252)
						(end 239.216184 -52.761134)
					)
					(arc
						(start 239.216184 -53.091334)
						(mid 239.238502 -53.145216)
						(end 239.292384 -53.167534)
					)
				)
			)
		)
	)
	(footprint ""
		(layer "F.Cu")
		(at 354.687632 -398.789398 180)
		(property "Reference" "R2675"
			(at 0 0 180)
			(layer "F.SilkS")
			(hide yes)
			(effects
				(font
					(size 1.27 1.27)
				)
			)
		)
		(property "Value" ""
			(at 0 0 180)
			(layer "F.Fab")
			(effects
				(font
					(size 1.27 1.27)
				)
			)
		)
		(duplicate_pad_numbers_are_jumpers no)
		(fp_line
			(start 0.7874 0.4064)
			(end -0.7874 0.4064)
			(stroke
				(width 0.1524)
				(type default)
			)
			(layer "F.SilkS")
		)
		(fp_line
			(start 0.7874 -0.4064)
			(end 0.7874 0.4064)
			(stroke
				(width 0.1524)
				(type default)
			)
			(layer "F.SilkS")
		)
		(fp_line
			(start -0.7874 0.4064)
			(end -0.7874 -0.4064)
			(stroke
				(width 0.1524)
				(type default)
			)
			(layer "F.SilkS")
		)
		(fp_line
			(start -0.7874 -0.4064)
			(end 0.7874 -0.4064)
			(stroke
				(width 0.1524)
				(type default)
			)
			(layer "F.SilkS")
		)
		(fp_line
			(start 0.67945 0.3048)
			(end 0.120396 0.3048)
			(stroke
				(width 0.1)
				(type default)
			)
			(layer "F.Fab")
		)
		(fp_line
			(start 0.67945 -0.3048)
			(end 0.67945 0.3048)
			(stroke
				(width 0.1)
				(type default)
			)
			(layer "F.Fab")
		)
		(fp_line
			(start 0.12065 -0.2794)
			(end 0.12065 -0.3048)
			(stroke
				(width 0.1)
				(type default)
			)
			(layer "F.Fab")
		)
		(fp_line
			(start 0.12065 -0.3048)
			(end 0.67945 -0.3048)
			(stroke
				(width 0.1)
				(type default)
			)
			(layer "F.Fab")
		)
		(fp_line
			(start 0.120396 0.3048)
			(end 0.120396 0.2794)
			(stroke
				(width 0.1)
				(type default)
			)
			(layer "F.Fab")
		)
		(fp_line
			(start 0.120396 0.2794)
			(end -0.12065 0.2794)
			(stroke
				(width 0.1)
				(type default)
			)
			(layer "F.Fab")
		)
		(fp_line
			(start -0.12065 0.3048)
			(end -0.67945 0.3048)
			(stroke
				(width 0.1)
				(type default)
			)
			(layer "F.Fab")
		)
		(fp_line
			(start -0.12065 0.2794)
			(end -0.12065 0.3048)
			(stroke
				(width 0.1)
				(type default)
			)
			(layer "F.Fab")
		)
		(fp_line
			(start -0.12065 -0.2794)
			(end 0.12065 -0.2794)
			(stroke
				(width 0.1)
				(type default)
			)
			(layer "F.Fab")
		)
		(fp_line
			(start -0.12065 -0.305054)
			(end -0.12065 -0.2794)
			(stroke
				(width 0.1)
				(type default)
			)
			(layer "F.Fab")
		)
		(fp_line
			(start -0.67945 0.3048)
			(end -0.67945 -0.305054)
			(stroke
				(width 0.1)
				(type default)
			)
			(layer "F.Fab")
		)
		(fp_line
			(start -0.67945 -0.305054)
			(end -0.12065 -0.305054)
			(stroke
				(width 0.1)
				(type default)
			)
			(layer "F.Fab")
		)
		(pad "1" smd circle
			(at -0.40005 0 180)
			(size 0 0)
			(layers "F.Cu" "F.Mask" "F.Paste")
			(net "I3C_BMC_SWB_BUF_R_SCL")
		)
		(pad "2" smd circle
			(at 0.40005 0 180)
			(size 0 0)
			(layers "F.Cu" "F.Mask" "F.Paste")
			(net "I3C_BMC_SWB_BUF_SCL")
		)
	)
	(footprint ""
		(layer "F.Cu")
		(at 141.372844 -343.018872 -90)
		(property "Reference" "PC485_P1_8"
			(at 0 0 270)
			(layer "F.SilkS")
			(hide yes)
			(effects
				(font
					(size 1.27 1.27)
				)
			)
		)
		(property "Value" ""
			(at 0 0 270)
			(layer "F.Fab")
			(effects
				(font
					(size 1.27 1.27)
				)
			)
		)
		(duplicate_pad_numbers_are_jumpers no)
		(fp_line
			(start -0.7874 0.4064)
			(end -0.7874 -0.4064)
			(stroke
				(width 0.1524)
				(type default)
			)
			(layer "F.SilkS")
		)
		(fp_line
			(start 0.7874 0.4064)
			(end -0.7874 0.4064)
			(stroke
				(width 0.1524)
				(type default)
			)
			(layer "F.SilkS")
		)
		(fp_line
			(start -0.7874 -0.4064)
			(end 0.7874 -0.4064)
			(stroke
				(width 0.1524)
				(type default)
			)
			(layer "F.SilkS")
		)
		(fp_line
			(start 0.7874 -0.4064)
			(end 0.7874 0.4064)
			(stroke
				(width 0.1524)
				(type default)
			)
			(layer "F.SilkS")
		)
		(fp_line
			(start -0.67945 0.3048)
			(end -0.67945 -0.305054)
			(stroke
				(width 0.1)
				(type default)
			)
			(layer "F.Fab")
		)
		(fp_line
			(start -0.12065 0.3048)
			(end -0.67945 0.3048)
			(stroke
				(width 0.1)
				(type default)
			)
			(layer "F.Fab")
		)
		(fp_line
			(start 0.120396 0.3048)
			(end 0.120396 0.2794)
			(stroke
				(width 0.1)
				(type default)
			)
			(layer "F.Fab")
		)
		(fp_line
			(start 0.67945 0.3048)
			(end 0.120396 0.3048)
			(stroke
				(width 0.1)
				(type default)
			)
			(layer "F.Fab")
		)
		(fp_line
			(start -0.12065 0.2794)
			(end -0.12065 0.3048)
			(stroke
				(width 0.1)
				(type default)
			)
			(layer "F.Fab")
		)
		(fp_line
			(start 0.120396 0.2794)
			(end -0.12065 0.2794)
			(stroke
				(width 0.1)
				(type default)
			)
			(layer "F.Fab")
		)
		(fp_line
			(start -0.12065 -0.2794)
			(end 0.12065 -0.2794)
			(stroke
				(width 0.1)
				(type default)
			)
			(layer "F.Fab")
		)
		(fp_line
			(start 0.12065 -0.2794)
			(end 0.12065 -0.3048)
			(stroke
				(width 0.1)
				(type default)
			)
			(layer "F.Fab")
		)
		(fp_line
			(start 0.12065 -0.3048)
			(end 0.67945 -0.3048)
			(stroke
				(width 0.1)
				(type default)
			)
			(layer "F.Fab")
		)
		(fp_line
			(start 0.67945 -0.3048)
			(end 0.67945 0.3048)
			(stroke
				(width 0.1)
				(type default)
			)
			(layer "F.Fab")
		)
		(fp_line
			(start -0.67945 -0.305054)
			(end -0.12065 -0.305054)
			(stroke
				(width 0.1)
				(type default)
			)
			(layer "F.Fab")
		)
		(fp_line
			(start -0.12065 -0.305054)
			(end -0.12065 -0.2794)
			(stroke
				(width 0.1)
				(type default)
			)
			(layer "F.Fab")
		)
		(pad "1" smd circle
			(at -0.40005 0 270)
			(size 0 0)
			(layers "F.Cu" "F.Mask" "F.Paste")
			(net "SW_P12V_PVCCIN_CPU1_FLT")
		)
		(pad "2" smd circle
			(at 0.40005 0 270)
			(size 0 0)
			(layers "F.Cu" "F.Mask" "F.Paste")
			(net "GND")
		)
	)
)
